FILE_TYPE = CONNECTIVITY;
{Allegro Design Entry HDL 16.6-p007 (v16-6-112F) 10/10/2012}
"PAGE_NUMBER" = 182;
0"NC";
1"P3E_CPU1_PE3_MP_TXN<15:8>";
2"P3E_CPU1_PE3_MP_RXN<15:8>";
3"P3E_CPU1_PE3_MP_RXP<15:8>";
4"P3E_CPU1_PE3_MP_TXP<15:8>";
5"GND\g";
6"GND\g";
7"FM_XRC_READY_N";
8"TP_IOA5";
9"IRQ_BOARD_BMC_ALERT_N";
10"P3E_CPU1_PE3_MP_RXP<8>";
11"P3E_CPU1_PE3_MP_C_TXP<12>";
12"P3E_CPU1_PE3_MP_TXP<11>";
13"P3E_CPU1_PE3_MP_RXN<10>";
14"FAN_TACH2_R";
15"FAN_TACH3_R";
16"FAN_TACH1_R";
17"TP_IOI4";
18"TP_IOF4";
19"FM_BB_BMC_MP_GPIO";
20"TP_IOG3";
21"P3E_CPU1_PE3_MP_RXN<9>";
22"TP_IOH3";
23"P3E_CPU1_PE3_MP_RXP<9>";
24"SMB_LAN_STBY_LVC3_SCL";
25"SMB_PEHPCPU1_STBY_LVC3_SDA";
26"P3E_CPU1_PE3_MP_TXP<14>";
27"P3E_CPU1_PE3_MP_TXP<13>";
28"P3E_CPU1_PE3_MP_TXN<13>";
29"P3E_CPU1_PE3_MP_TXN<11>";
30"P3E_CPU1_PE3_MP_C_TXN<11>";
31"P3E_CPU1_PE3_MP_TXP<15>";
32"P3E_CPU1_PE3_MP_C_TXP<15>";
33"P3E_CPU1_PE3_MP_TXN<15>";
34"P3E_CPU1_PE3_MP_TXN<14>";
35"P3E_CPU1_PE3_MP_C_TXN<15>";
36"P3E_CPU1_PE3_MP_C_TXP<14>";
37"P3E_CPU1_PE3_MP_TXP<8>";
38"P3E_CPU1_PE3_MP_TXN<9>";
39"SMB_LAN_STBY_LVC3_SDA";
40"P3E_CPU1_PE3_MP_TXN<12>";
41"P3E_CPU1_PE3_MP_TXP<12>";
42"SMB_LAN_STBY_LVC3_SDA";
43"IRQ_BOARD_BMC_ALERT_N";
44"FM_BMC_READY_N";
45"FM_XRC_READY_N";
46"SMB_LAN_STBY_LVC3_SCL";
47"FAN_PWM_OUT_SYS0_R1";
48"FAN_TACH0_R";
49"P3E_CPU1_PE3_MP_TXP<10>";
50"P3E_CPU1_PE3_MP_TXP<9>";
51"P3E_CPU1_PE3_MP_TXN<10>";
52"P3E_CPU1_PE3_MP_C_TXN<9>";
53"P3E_CPU1_PE3_MP_C_TXP<8>";
54"P3E_CPU1_PE3_MP_C_TXN<8>";
55"P3E_CPU1_PE3_MP_C_TXP<13>";
56"P3E_CPU1_PE3_MP_C_TXN<13>";
57"P3E_CPU1_PE3_MP_C_TXN<12>";
58"P3E_CPU1_PE3_MP_C_TXN<14>";
59"TP_FM_WAKE_N";
60"TP_IOH4";
61"TP_IOE4";
62"P3E_CPU1_PE3_MP_RXN<8>";
63"P3E_CPU1_PE3_MP_RXP<10>";
64"P3E_CPU1_PE3_MP_RXP<11>";
65"P3E_CPU1_PE3_MP_RXP<12>";
66"P3E_CPU1_PE3_MP_RXP<13>";
67"P3E_CPU1_PE3_MP_RXN<12>";
68"P3E_CPU1_PE3_MP_RXN<11>";
69"P3E_CPU1_PE3_MP_RXN<13>";
70"P3E_CPU1_PE3_MP_RXP<14>";
71"P3E_CPU1_PE3_MP_RXP<15>";
72"P3E_CPU1_PE3_MP_RXN<15>";
73"P3E_CPU1_PE3_MP_RXN<14>";
74"P3E_CPU1_PE3_MP_C_TXN<10>";
75"P3E_CPU1_PE3_MP_C_TXP<10>";
76"P3E_CPU1_PE3_MP_C_TXP<9>";
77"P3E_CPU1_PE3_MP_C_TXP<11>";
78"SMB_PEHPCPU1_STBY_LVC3_SCL";
79"FM_XRC_PRESENT_N";
80"P3E_CPU1_PE3_MP_TXN<8>";
%"RES"
"1","(-7000,350)","0","mstr_discrete","I10";
;
PACK_TYPE"0402"
MATERIAL"EMPTY"
PART_NUMBER"G21497-005"
TOLERANCE"5%"
VALUE"0.0"
WATTAGE"1/16W"
LOCATION"R1C11"
SEC_TYPE"0402"
SEC"1"
NO_XNET_CONNECTION"1"
ROOM"IO_SLOT"
CDS_LIB"mstr_discrete"
CDS_LOCATION"R1C11"
CDS_SEC"1";
"B"
$PN"2"16;
"A"
$PN"1"46;
%"GND"
"1","(-5850,750)","0","mstr_symbols","I19";
;
SIZE"1B"
CDS_LIB"mstr_symbols"
BODY_TYPE"PLUMBING"
ROOM"P2V5_LAN_AUX_VR"
HDL_POWER"GND"
BOM_COST"NT_BASE_VRD"
VOLTAGE"0";
"A\NAC"5;
%"TAP"
"1","(-6350,1975)","2","mstr_standard","I20";
;
BODY_TYPE"PLUMBING"
CDS_LIB"mstr_standard"
HDL_TAP"TRUE";
"B \NAC \NWC"2;
"S \NAC"
BN"14"73;
%"TAP"
"1","(-6350,1875)","2","mstr_standard","I21";
;
CDS_LIB"mstr_standard"
BODY_TYPE"PLUMBING"
HDL_TAP"TRUE";
"B \NAC \NWC"2;
"S \NAC"
BN"15"72;
%"TAP"
"1","(-6350,2175)","2","mstr_standard","I22";
;
CDS_LIB"mstr_standard"
BODY_TYPE"PLUMBING"
HDL_TAP"TRUE";
"B \NAC \NWC"2;
"S \NAC"
BN"13"69;
%"TAP"
"1","(-6350,2375)","2","mstr_standard","I23";
;
CDS_LIB"mstr_standard"
BODY_TYPE"PLUMBING"
HDL_TAP"TRUE";
"B \NAC \NWC"2;
"S \NAC"
BN"12"67;
%"TAP"
"1","(-6100,2025)","2","mstr_standard","I24";
;
BODY_TYPE"PLUMBING"
CDS_LIB"mstr_standard"
HDL_TAP"TRUE";
"B \NAC \NWC"3;
"S \NAC"
BN"14"70;
%"TAP"
"1","(-6100,1825)","2","mstr_standard","I25";
;
BODY_TYPE"PLUMBING"
CDS_LIB"mstr_standard"
HDL_TAP"TRUE";
"B \NAC \NWC"3;
"S \NAC"
BN"15"71;
%"TAP"
"1","(-6100,2225)","2","mstr_standard","I26";
;
BODY_TYPE"PLUMBING"
CDS_LIB"mstr_standard"
HDL_TAP"TRUE";
"B \NAC \NWC"3;
"S \NAC"
BN"13"66;
%"TAP"
"1","(-6100,2325)","2","mstr_standard","I27";
;
BODY_TYPE"PLUMBING"
CDS_LIB"mstr_standard"
HDL_TAP"TRUE";
"B \NAC \NWC"3;
"S \NAC"
BN"12"65;
%"TAP"
"1","(-6100,2475)","2","mstr_standard","I28";
;
BODY_TYPE"PLUMBING"
CDS_LIB"mstr_standard"
HDL_TAP"TRUE";
"B \NAC \NWC"3;
"S \NAC"
BN"11"64;
%"TAP"
"1","(-6350,2725)","2","mstr_standard","I29";
;
BODY_TYPE"PLUMBING"
CDS_LIB"mstr_standard"
HDL_TAP"TRUE";
"B \NAC \NWC"2;
"S \NAC"
BN"10"13;
%"TAP"
"1","(-6350,2925)","2","mstr_standard","I30";
;
CDS_LIB"mstr_standard"
BODY_TYPE"PLUMBING"
HDL_TAP"TRUE";
"B \NAC \NWC"2;
"S \NAC"
BN"9"21;
%"TAP"
"1","(-6350,3075)","2","mstr_standard","I31";
;
CDS_LIB"mstr_standard"
BODY_TYPE"PLUMBING"
HDL_TAP"TRUE";
"B \NAC \NWC"2;
"S \NAC"
BN"8"62;
%"TAP"
"1","(-6100,2775)","2","mstr_standard","I32";
;
BODY_TYPE"PLUMBING"
CDS_LIB"mstr_standard"
HDL_TAP"TRUE";
"B \NAC \NWC"3;
"S \NAC"
BN"10"63;
%"TAP"
"1","(-6100,2875)","2","mstr_standard","I33";
;
BODY_TYPE"PLUMBING"
CDS_LIB"mstr_standard"
HDL_TAP"TRUE";
"B \NAC \NWC"3;
"S \NAC"
BN"9"23;
%"TAP"
"1","(-6100,3025)","2","mstr_standard","I34";
;
BODY_TYPE"PLUMBING"
CDS_LIB"mstr_standard"
HDL_TAP"TRUE";
"B \NAC \NWC"3;
"S \NAC"
BN"8"10;
%"GND"
"1","(-4200,700)","0","mstr_symbols","I35";
;
VOLTAGE"0"
BOM_COST"NT_BASE_VRD"
CDS_LIB"mstr_symbols"
SIZE"1B"
BODY_TYPE"PLUMBING"
ROOM"P2V5_LAN_AUX_VR"
HDL_POWER"GND";
"A\NAC"6;
%"CAP"
"2","(-3400,1125)","0","mstr_discrete","I36";
;
TOLERANCE"10%"
MATERIAL"X7R"
PART_NUMBER"A36096-155"
PACK_TYPE"0402"
VOLTAGE"16V"
LOCATION"C9N2"
VALUE"0.22UF"
SEC_TYPE"0402"
SEC"1"
BOM_COST"IO_SLOT"
ROOM"IO_SLOT"
CDS_LIB"mstr_discrete"
CDS_LOCATION"C9N2"
CDS_SEC"1";
"A"
$PN"1"74;
"B"
$PN"2"51;
%"CAP"
"2","(-3400,1275)","0","mstr_discrete","I37";
;
PART_NUMBER"A36096-155"
LOCATION"C9N12"
PACK_TYPE"0402"
TOLERANCE"10%"
MATERIAL"X7R"
VOLTAGE"16V"
VALUE"0.22UF"
SEC"1"
SEC_TYPE"0402"
BOM_COST"IO_SLOT"
ROOM"IO_SLOT"
CDS_LOCATION"C9N12"
CDS_LIB"mstr_discrete"
CDS_SEC"1";
"A"
$PN"1"76;
"B"
$PN"2"50;
%"CAP"
"2","(-3400,1425)","0","mstr_discrete","I38";
;
PART_NUMBER"A36096-155"
LOCATION"C9N17"
TOLERANCE"10%"
PACK_TYPE"0402"
MATERIAL"X7R"
VOLTAGE"16V"
VALUE"0.22UF"
ROOM"IO_SLOT"
SEC"1"
SEC_TYPE"0402"
BOM_COST"IO_SLOT"
CDS_LOCATION"C9N17"
CDS_LIB"mstr_discrete"
CDS_SEC"1";
"A"
$PN"1"53;
"B"
$PN"2"37;
%"CAP"
"2","(-2925,1475)","0","mstr_discrete","I39";
;
LOCATION"C9N18"
VALUE"0.22UF"
PART_NUMBER"A36096-155"
MATERIAL"X7R"
VOLTAGE"16V"
PACK_TYPE"0402"
TOLERANCE"10%"
ROOM"IO_SLOT"
CDS_LOCATION"C9N18"
SEC"1"
BOM_COST"IO_SLOT"
SEC_TYPE"0402"
CDS_LIB"mstr_discrete"
CDS_SEC"1";
"A"
$PN"1"54;
"B"
$PN"2"80;
%"CAP"
"2","(-2925,1175)","0","mstr_discrete","I40";
;
LOCATION"C9N1"
VALUE"0.22UF"
PACK_TYPE"0402"
PART_NUMBER"A36096-155"
TOLERANCE"10%"
MATERIAL"X7R"
VOLTAGE"16V"
SEC_TYPE"0402"
SEC"1"
ROOM"IO_SLOT"
BOM_COST"IO_SLOT"
CDS_LIB"mstr_discrete"
CDS_LOCATION"C9N1"
CDS_SEC"1";
"A"
$PN"1"75;
"B"
$PN"2"49;
%"CAP"
"2","(-2925,1325)","0","mstr_discrete","I41";
;
VALUE"0.22UF"
MATERIAL"X7R"
PACK_TYPE"0402"
LOCATION"C9N15"
PART_NUMBER"A36096-155"
TOLERANCE"10%"
VOLTAGE"16V"
SEC_TYPE"0402"
SEC"1"
ROOM"IO_SLOT"
BOM_COST"IO_SLOT"
CDS_LOCATION"C9N15"
CDS_LIB"mstr_discrete"
CDS_SEC"1";
"A"
$PN"1"52;
"B"
$PN"2"38;
%"CAP"
"2","(-3400,1725)","0","mstr_discrete","I42";
;
PACK_TYPE"0402"
PART_NUMBER"A36096-155"
MATERIAL"X7R"
LOCATION"C9N6"
TOLERANCE"10%"
VALUE"0.22UF"
VOLTAGE"16V"
SEC"1"
ROOM"IO_SLOT"
SEC_TYPE"0402"
BOM_COST"IO_SLOT"
CDS_LOCATION"C9N6"
CDS_LIB"mstr_discrete"
CDS_SEC"1";
"A"
$PN"1"56;
"B"
$PN"2"28;
%"CAP"
"2","(-3400,1825)","0","mstr_discrete","I43";
;
LOCATION"C9N14"
PACK_TYPE"0402"
VOLTAGE"16V"
PART_NUMBER"A36096-155"
TOLERANCE"10%"
MATERIAL"X7R"
VALUE"0.22UF"
SEC"1"
SEC_TYPE"0402"
ROOM"IO_SLOT"
BOM_COST"IO_SLOT"
CDS_LOCATION"C9N14"
CDS_LIB"mstr_discrete"
CDS_SEC"1";
"A"
$PN"1"11;
"B"
$PN"2"41;
%"CAP"
"2","(-3400,1975)","0","mstr_discrete","I44";
;
PACK_TYPE"0402"
TOLERANCE"10%"
PART_NUMBER"A36096-155"
MATERIAL"X7R"
VOLTAGE"16V"
VALUE"0.22UF"
LOCATION"C9N4"
ROOM"IO_SLOT"
CDS_LOCATION"C9N4"
SEC"1"
SEC_TYPE"0402"
BOM_COST"IO_SLOT"
CDS_LIB"mstr_discrete"
CDS_SEC"1";
"A"
$PN"1"77;
"B"
$PN"2"12;
%"CAP"
"2","(-2925,1675)","0","mstr_discrete","I45";
;
PACK_TYPE"0402"
PART_NUMBER"A36096-155"
VALUE"0.22UF"
LOCATION"C9N5"
VOLTAGE"16V"
MATERIAL"X7R"
TOLERANCE"10%"
ROOM"IO_SLOT"
SEC"1"
BOM_COST"IO_SLOT"
SEC_TYPE"0402"
CDS_LOCATION"C9N5"
CDS_LIB"mstr_discrete"
CDS_SEC"1";
"A"
$PN"1"55;
"B"
$PN"2"27;
%"CAP"
"2","(-2925,1875)","0","mstr_discrete","I46";
;
LOCATION"C9N16"
PART_NUMBER"A36096-155"
PACK_TYPE"0402"
TOLERANCE"10%"
MATERIAL"X7R"
VOLTAGE"16V"
VALUE"0.22UF"
ROOM"IO_SLOT"
SEC"1"
SEC_TYPE"0402"
BOM_COST"IO_SLOT"
CDS_LOCATION"C9N16"
CDS_LIB"mstr_discrete"
CDS_SEC"1";
"A"
$PN"1"57;
"B"
$PN"2"40;
%"CAP"
"2","(-2925,2025)","0","mstr_discrete","I47";
;
LOCATION"C9N3"
TOLERANCE"10%"
PART_NUMBER"A36096-155"
PACK_TYPE"0402"
MATERIAL"X7R"
VALUE"0.22UF"
VOLTAGE"16V"
SEC_TYPE"0402"
SEC"1"
ROOM"IO_SLOT"
CDS_LOCATION"C9N3"
BOM_COST"IO_SLOT"
CDS_LIB"mstr_discrete"
CDS_SEC"1";
"A"
$PN"1"30;
"B"
$PN"2"29;
%"CAP"
"2","(-3400,2175)","0","mstr_discrete","I48";
;
TOLERANCE"10%"
PACK_TYPE"0402"
MATERIAL"X7R"
VOLTAGE"16V"
VALUE"0.22UF"
PART_NUMBER"A36096-155"
LOCATION"C9N7"
ROOM"IO_SLOT"
SEC"1"
BOM_COST"IO_SLOT"
SEC_TYPE"0402"
CDS_LIB"mstr_discrete"
CDS_LOCATION"C9N7"
CDS_SEC"1";
"A"
$PN"1"32;
"B"
$PN"2"31;
%"CAP"
"2","(-3400,2325)","0","mstr_discrete","I49";
;
MATERIAL"X7R"
VOLTAGE"16V"
TOLERANCE"10%"
PACK_TYPE"0402"
VALUE"0.22UF"
LOCATION"C9N10"
PART_NUMBER"A36096-155"
SEC_TYPE"0402"
SEC"1"
ROOM"IO_SLOT"
BOM_COST"IO_SLOT"
CDS_LIB"mstr_discrete"
CDS_LOCATION"C9N10"
CDS_SEC"1";
"A"
$PN"1"36;
"B"
$PN"2"26;
%"CAP"
"2","(-2925,2225)","0","mstr_discrete","I52";
;
VALUE"0.22UF"
LOCATION"C9N9"
PART_NUMBER"A36096-155"
TOLERANCE"10%"
MATERIAL"X7R"
VOLTAGE"16V"
PACK_TYPE"0402"
ROOM"IO_SLOT"
CDS_LOCATION"C9N9"
SEC"1"
SEC_TYPE"0402"
BOM_COST"IO_SLOT"
CDS_LIB"mstr_discrete"
CDS_SEC"1";
"A"
$PN"1"35;
"B"
$PN"2"33;
%"CAP"
"2","(-2925,2375)","0","mstr_discrete","I53";
;
VOLTAGE"16V"
PART_NUMBER"A36096-155"
LOCATION"C9N8"
MATERIAL"X7R"
TOLERANCE"10%"
PACK_TYPE"0402"
VALUE"0.22UF"
SEC_TYPE"0402"
SEC"1"
ROOM"IO_SLOT"
BOM_COST"IO_SLOT"
CDS_LOCATION"C9N8"
CDS_LIB"mstr_discrete"
CDS_SEC"1";
"A"
$PN"1"58;
"B"
$PN"2"34;
%"TAP"
"6","(-2175,1175)","2","mstr_standard","I59";
;
CDS_LIB"mstr_standard"
BODY_TYPE"PLUMBING"
HDL_TAP"TRUE";
"B \NAC \NWC"4;
"S \NAC"
BN"10"49;
%"RES"
"1","(-7000,-175)","0","mstr_discrete","I6";
;
PACK_TYPE"0402"
MATERIAL"EMPTY"
PART_NUMBER"G21497-005"
TOLERANCE"5%"
VALUE"0.0"
WATTAGE"1/16W"
LOCATION"R1C31"
NO_XNET_CONNECTION"1"
SEC"1"
SEC_TYPE"0402"
ROOM"IO_SLOT"
CDS_LIB"mstr_discrete"
CDS_LOCATION"R1C31"
CDS_SEC"1";
"B"
$PN"2"48;
"A"
$PN"1"45;
%"TAP"
"6","(-2175,1275)","2","mstr_standard","I60";
;
CDS_LIB"mstr_standard"
BODY_TYPE"PLUMBING"
HDL_TAP"TRUE";
"B \NAC \NWC"4;
"S \NAC"
BN"9"50;
%"TAP"
"6","(-2175,1425)","2","mstr_standard","I61";
;
CDS_LIB"mstr_standard"
BODY_TYPE"PLUMBING"
HDL_TAP"TRUE";
"B \NAC \NWC"4;
"S \NAC"
BN"8"37;
%"TAP"
"6","(-1925,1125)","2","mstr_standard","I62";
;
CDS_LIB"mstr_standard"
BODY_TYPE"PLUMBING"
HDL_TAP"TRUE";
"B \NAC \NWC"1;
"S \NAC"
BN"10"51;
%"TAP"
"6","(-1925,1325)","2","mstr_standard","I63";
;
CDS_LIB"mstr_standard"
BODY_TYPE"PLUMBING"
HDL_TAP"TRUE";
"B \NAC \NWC"1;
"S \NAC"
BN"9"38;
%"TAP"
"6","(-1925,1475)","2","mstr_standard","I64";
;
CDS_LIB"mstr_standard"
BODY_TYPE"PLUMBING"
HDL_TAP"TRUE";
"B \NAC \NWC"1;
"S \NAC"
BN"8"80;
%"TAP"
"6","(-2175,1675)","2","mstr_standard","I65";
;
CDS_LIB"mstr_standard"
BODY_TYPE"PLUMBING"
HDL_TAP"TRUE";
"B \NAC \NWC"4;
"S \NAC"
BN"13"27;
%"TAP"
"6","(-2175,1825)","2","mstr_standard","I66";
;
CDS_LIB"mstr_standard"
BODY_TYPE"PLUMBING"
HDL_TAP"TRUE";
"B \NAC \NWC"4;
"S \NAC"
BN"12"41;
%"TAP"
"6","(-2175,1975)","2","mstr_standard","I67";
;
CDS_LIB"mstr_standard"
BODY_TYPE"PLUMBING"
HDL_TAP"TRUE";
"B \NAC \NWC"4;
"S \NAC"
BN"11"12;
%"TAP"
"6","(-2175,2175)","2","mstr_standard","I68";
;
CDS_LIB"mstr_standard"
BODY_TYPE"PLUMBING"
HDL_TAP"TRUE";
"B \NAC \NWC"4;
"S \NAC"
BN"15"31;
%"TAP"
"6","(-2175,2325)","2","mstr_standard","I69";
;
CDS_LIB"mstr_standard"
BODY_TYPE"PLUMBING"
HDL_TAP"TRUE";
"B \NAC \NWC"4;
"S \NAC"
BN"14"26;
%"RES"
"1","(-7000,-25)","0","mstr_discrete","I7";
;
PART_NUMBER"G21497-005"
PACK_TYPE"0402"
MATERIAL"EMPTY"
TOLERANCE"5%"
VALUE"0.0"
LOCATION"R1F9"
WATTAGE"1/16W"
ROOM"IO_SLOT"
NO_XNET_CONNECTION"1"
SEC"1"
SEC_TYPE"0402"
CDS_LIB"mstr_discrete"
CDS_LOCATION"R1F9"
CDS_SEC"1";
"B"
$PN"2"47;
"A"
$PN"1"44;
%"TAP"
"6","(-1925,1725)","2","mstr_standard","I70";
;
CDS_LIB"mstr_standard"
BODY_TYPE"PLUMBING"
HDL_TAP"TRUE";
"B \NAC \NWC"1;
"S \NAC"
BN"13"28;
%"TAP"
"6","(-1925,1875)","2","mstr_standard","I71";
;
CDS_LIB"mstr_standard"
BODY_TYPE"PLUMBING"
HDL_TAP"TRUE";
"B \NAC \NWC"1;
"S \NAC"
BN"12"40;
%"TAP"
"6","(-1925,2025)","2","mstr_standard","I72";
;
CDS_LIB"mstr_standard"
BODY_TYPE"PLUMBING"
HDL_TAP"TRUE";
"B \NAC \NWC"1;
"S \NAC"
BN"11"29;
%"TAP"
"6","(-1925,2225)","2","mstr_standard","I73";
;
CDS_LIB"mstr_standard"
BODY_TYPE"PLUMBING"
HDL_TAP"TRUE";
"B \NAC \NWC"1;
"S \NAC"
BN"15"33;
%"TAP"
"6","(-1925,2375)","2","mstr_standard","I74";
;
CDS_LIB"mstr_standard"
BODY_TYPE"PLUMBING"
HDL_TAP"TRUE";
"B \NAC \NWC"1;
"S \NAC"
BN"14"34;
%"TAP"
"1","(-6350,2525)","2","mstr_standard","I77";
;
BODY_TYPE"PLUMBING"
CDS_LIB"mstr_standard"
HDL_TAP"TRUE";
"B \NAC \NWC"2;
"S \NAC"
BN"11"68;
%"DM-FCI-CONN76-8R-GP-U-01"
"1","(-5000,2050)","0","w_hdl","I79";
;
CDS_SEC"1"
CDS_LOCATION"J1C1"
CONFIG"H22707-001"
NEW_PN"20.82092.076"
LOCATION"J1C1"
VALUE"DM-FCI-CONN76-8R-GP-U-01"
PACK_TYPE"CONN-G4"
SEC"1"
SEC_TYPE"CONN-G4"
PART_NUMBER"ZZ.82092.07601"
CDS_LIB"w_hdl"
CDS_LMAN_SYM_OUTLINE"-475,1225,475,-1225";
"MB_SLOT_ID1"
$PN"G5"79;
"MB_SLOT_ID2"
$PN"H5"7;
"PCIE_PERST# \B"
$PN"I5"6;
"PMBUS_ALERT# \B"
$PN"A6"6;
"PCIE_CLK_100M_DN"
$PN"I4"17;
"J4"
$PN"J4"5;
"PCIE_CLK_100M_DP"
$PN"H4"60;
"GND14"
$PN"G4"5;
"FAN_PWM0"
$PN"F4"18;
"FAN_TACH1"
$PN"C4"19;
"MATED_IN# \B"
$PN"E4"61;
"FAN_TACH0"
$PN"D4"5;
"FAN_TACH2"
$PN"B4"59;
"FAN_TACH3"
$PN"A4"5;
"MB_ON# \B"
$PN"I3"5;
"COM_RX"
$PN"H3"22;
"GND11"
$PN"F3"5;
"COM_TX"
$PN"G3"20;
"PCIE_RX_DN7"
$PN"E3"71;
"GND4"
$PN"C3"5;
"PCIE_RX_DP7"
$PN"D3"72;
"PCIE_RX_DN6"
$PN"B3"73;
"PCIE_RX_DP6"
$PN"A3"70;
"J2"
$PN"J2"5;
"PCIE_RX_DN5"
$PN"I2"69;
"PCIE_RX_DN4"
$PN"F2"65;
"PCIE_RX_DP5"
$PN"H2"66;
"GND13"
$PN"G2"5;
"GND7"
$PN"D2"5;
"PCIE_RX_DP4"
$PN"E2"67;
"PCIE_RX_DN3"
$PN"C2"64;
"GND1"
$PN"A2"5;
"PCIE_RX_DP3"
$PN"B2"68;
"GND17"
$PN"I1"5;
"PCIE_RX_DN2"
$PN"H1"13;
"PCIE_RX_DP2"
$PN"G1"63;
"GND10"
$PN"F1"5;
"PCIE_RX_DP1"
$PN"D1"21;
"PCIE_RX_DN1"
$PN"E1"23;
"GND3"
$PN"C1"5;
"PCIE_RX_DN0"
$PN"B1"10;
"PCIE_RX_DP0"
$PN"A1"62;
"J8"
$PN"J8"6;
"PCIE_TX_DN2"
$PN"I8"74;
"PCIE_TX_DP2"
$PN"H8"75;
"GND16"
$PN"G8"6;
"PCIE_TX_DN1"
$PN"F8"76;
"GND9"
$PN"D8"6;
"PCIE_TX_DP1"
$PN"E8"52;
"PCIE_TX_DN0"
$PN"C8"53;
"GND2"
$PN"A8"6;
"PCIE_TX_DP0"
$PN"B8"54;
"PCIE_TX_DN5"
$PN"H7"55;
"GND18"
$PN"I7"6;
"GND12"
$PN"F7"6;
"PCIE_TX_DP5"
$PN"G7"56;
"PCIE_TX_DN4"
$PN"E7"11;
"GND6"
$PN"C7"6;
"PCIE_TX_DP4"
$PN"D7"57;
"PCIE_TX_DN3"
$PN"B7"77;
"PCIE_TX_DP3"
$PN"A7"30;
"PCIE_TX_DN7"
$PN"I6"32;
"J6"
$PN"J6"6;
"PCIE_TX_DP7"
$PN"H6"35;
"GND15"
$PN"G6"6;
"PCIE_TX_DN6"
$PN"F6"36;
"GND8"
$PN"D6"6;
"PCIE_TX_DP6"
$PN"E6"58;
"PMBUS_CLK"
$PN"C6"78;
"PMBUS_DATA"
$PN"B6"25;
"MNG_RX_DP"
$PN"D5"39;
"MNG_RX_DN"
$PN"E5"24;
"GND5"
$PN"C5"6;
"MNG_TX_DN"
$PN"B5"9;
"MNG_TX_DP"
$PN"A5"8;
"MB_SLOT_ID0"
$PN"F5"6;
%"RES"
"1","(-7000,100)","0","mstr_discrete","I8";
;
PACK_TYPE"0402"
MATERIAL"EMPTY"
TOLERANCE"5%"
VALUE"0.0"
WATTAGE"1/16W"
LOCATION"R1C9"
PART_NUMBER"G21497-005"
NO_XNET_CONNECTION"1"
SEC"1"
SEC_TYPE"0402"
ROOM"IO_SLOT"
CDS_LIB"mstr_discrete"
CDS_LOCATION"R1C9"
CDS_SEC"1";
"B"
$PN"2"14;
"A"
$PN"1"43;
%"RES"
"1","(-7000,225)","0","mstr_discrete","I9";
;
PACK_TYPE"0402"
MATERIAL"EMPTY"
PART_NUMBER"G21497-005"
TOLERANCE"5%"
VALUE"0.0"
LOCATION"R1C10"
WATTAGE"1/16W"
ROOM"IO_SLOT"
SEC_TYPE"0402"
SEC"1"
NO_XNET_CONNECTION"1"
CDS_LIB"mstr_discrete"
CDS_LOCATION"R1C10"
CDS_SEC"1";
"B"
$PN"2"15;
"A"
$PN"1"42;
END.
